# T6G (Grand Teton) — schematic netlist excerpt (pin names and nets, part order shuffled) for the footprints in the layout excerpt that follows; sources: Cadence DE-HDL packaged netlist, KiCad conversion of 04192023_DAF0TMB3IC0_F0TG_MB_C_brd_V02_OCP.brd

R6823  Q_RES  0 5% CHIP  pkg 0402LF  page 81 : A = RST_RT_CPU0_P2_PERST_R2_N ; B = RST_RT_CPU0_P2_PERST_R_N
PC213_1  Q_CAP  22UF 16V 20% X6S  pkg C0805  page 208 : A = SW_P12V_AUX_PVDD11_S3_P0_FLT ; B = GND
PC555_4  Q_CAP  22UF 16V 20% X6S  pkg C0805  page 195 : A = SW_P12V_AUX_PVDDCR_CPU0_P0_FLT ; B = GND

(kicad_pcb
	(version 20260206)
	(generator "pcbnew")
	(generator_version "10.0")
	(general
		(thickness 1.6)
		(legacy_teardrops no)
	)
	(paper "A4")
	(title_block
		(title "04192023_DAF0TMB3IC0_F0TG_MB_C_brd_V02_OCP.brd")
		(comment 1 "Grand Teton / footprints 6190-6192 of 8354")
	)
	(layers
		(0 "F.Cu" signal "TOP")
		(4 "In1.Cu" signal "GND")
		(6 "In2.Cu" signal "IN1")
		(8 "In3.Cu" signal "GND1")
		(10 "In4.Cu" signal "IN2")
		(12 "In5.Cu" signal "GND2")
		(14 "In6.Cu" signal "IN3")
		(16 "In7.Cu" signal "GND3")
		(18 "In8.Cu" signal "VCC")
		(20 "In9.Cu" signal "VCC1")
		(22 "In10.Cu" signal "GND4")
		(24 "In11.Cu" signal "IN4")
		(26 "In12.Cu" signal "GND5")
		(28 "In13.Cu" signal "IN5")
		(30 "In14.Cu" signal "GND6")
		(32 "In15.Cu" signal "IN6")
		(34 "In16.Cu" signal "GND7")
		(2 "B.Cu" signal "BOTTOM")
		(9 "F.Adhes" user "F.Adhesive")
		(11 "B.Adhes" user "B.Adhesive")
		(13 "F.Paste" user "Package Geometry/Pastemask Top")
		(15 "B.Paste" user "Package Geometry/Pastemask Bottom")
		(5 "F.SilkS" user "Ref Des/Silkscreen Top")
		(7 "B.SilkS" user "Ref Des/Silkscreen Bottom")
		(1 "F.Mask" user "Board Geometry/Soldermask Top")
		(3 "B.Mask" user "Board Geometry/Soldermask Bottom")
		(17 "Dwgs.User" user "User.Drawings")
		(19 "Cmts.User" user "User.Comments")
		(21 "Eco1.User" user "User.Eco1")
		(23 "Eco2.User" user "User.Eco2")
		(25 "Edge.Cuts" user "Board Geometry/Outline")
		(27 "Margin" user)
		(31 "F.CrtYd" user "Package Geometry/Place Bound Top")
		(29 "B.CrtYd" user "Package Geometry/Place Bound Bottom")
		(35 "F.Fab" user "Ref Des/Assembly Top")
		(33 "B.Fab" user "Ref Des/Assembly Bottom")
	)
	(footprint ""
		(layer "B.Cu")
		(at 424.670474 -351.032826 90)
		(property "Reference" "PC213_1"
			(at 0 0 90)
			(layer "B.SilkS")
			(hide yes)
			(effects
				(font
					(size 1.27 1.27)
				)
				(justify mirror)
			)
		)
		(property "Value" ""
			(at 0 0 90)
			(layer "B.Fab")
			(effects
				(font
					(size 1.27 1.27)
				)
				(justify mirror)
			)
		)
		(duplicate_pad_numbers_are_jumpers no)
		(fp_line
			(start 1.524 -0.762)
			(end -1.524 -0.762)
			(stroke
				(width 0.1524)
				(type default)
			)
			(layer "B.SilkS")
		)
		(fp_line
			(start -1.524 -0.762)
			(end -1.524 0.762)
			(stroke
				(width 0.1524)
				(type default)
			)
			(layer "B.SilkS")
		)
		(fp_line
			(start 1.524 0.762)
			(end 1.524 -0.762)
			(stroke
				(width 0.1524)
				(type default)
			)
			(layer "B.SilkS")
		)
		(fp_line
			(start -1.524 0.762)
			(end 1.524 0.762)
			(stroke
				(width 0.1524)
				(type default)
			)
			(layer "B.SilkS")
		)
		(fp_line
			(start 1.1049 -0.724916)
			(end 1.1049 0.724916)
			(stroke
				(width 0.1)
				(type default)
			)
			(layer "B.Fab")
		)
		(fp_line
			(start -1.1049 -0.724916)
			(end 1.1049 -0.724916)
			(stroke
				(width 0.1)
				(type default)
			)
			(layer "B.Fab")
		)
		(fp_line
			(start 1.1049 0.724916)
			(end -1.1049 0.724916)
			(stroke
				(width 0.1)
				(type default)
			)
			(layer "B.Fab")
		)
		(fp_line
			(start -1.1049 0.724916)
			(end -1.1049 -0.724916)
			(stroke
				(width 0.1)
				(type default)
			)
			(layer "B.Fab")
		)
		(pad "1" smd rect
			(at 0.889 0 90)
			(size 1.016 1.27)
			(layers "B.Cu" "B.Mask" "B.Paste")
			(net "SW_P12V_AUX_PVDD11_S3_P0_FLT")
		)
		(pad "2" smd rect
			(at -0.889 0 90)
			(size 1.016 1.27)
			(layers "B.Cu" "B.Mask" "B.Paste")
			(net "GND")
		)
	)
	(footprint ""
		(layer "B.Cu")
		(at 205.150466 -128.082294 180)
		(property "Reference" "R6823"
			(at 0 0 0)
			(layer "B.SilkS")
			(hide yes)
			(effects
				(font
					(size 1.27 1.27)
				)
				(justify mirror)
			)
		)
		(property "Value" ""
			(at 0 0 0)
			(layer "B.Fab")
			(effects
				(font
					(size 1.27 1.27)
				)
				(justify mirror)
			)
		)
		(duplicate_pad_numbers_are_jumpers no)
		(fp_line
			(start 0.7874 0.4064)
			(end 0.7874 -0.4064)
			(stroke
				(width 0.1524)
				(type default)
			)
			(layer "B.SilkS")
		)
		(fp_line
			(start 0.7874 -0.4064)
			(end -0.7874 -0.4064)
			(stroke
				(width 0.1524)
				(type default)
			)
			(layer "B.SilkS")
		)
		(fp_line
			(start -0.7874 0.4064)
			(end 0.7874 0.4064)
			(stroke
				(width 0.1524)
				(type default)
			)
			(layer "B.SilkS")
		)
		(fp_line
			(start -0.7874 -0.4064)
			(end -0.7874 0.4064)
			(stroke
				(width 0.1524)
				(type default)
			)
			(layer "B.SilkS")
		)
		(fp_line
			(start 0.67945 0.3048)
			(end 0.67945 -0.305054)
			(stroke
				(width 0.1)
				(type default)
			)
			(layer "B.Fab")
		)
		(fp_line
			(start 0.67945 -0.305054)
			(end 0.12065 -0.305054)
			(stroke
				(width 0.1)
				(type default)
			)
			(layer "B.Fab")
		)
		(fp_line
			(start 0.12065 0.3048)
			(end 0.67945 0.3048)
			(stroke
				(width 0.1)
				(type default)
			)
			(layer "B.Fab")
		)
		(fp_line
			(start 0.12065 0.2794)
			(end 0.12065 0.3048)
			(stroke
				(width 0.1)
				(type default)
			)
			(layer "B.Fab")
		)
		(fp_line
			(start 0.12065 -0.2794)
			(end -0.12065 -0.2794)
			(stroke
				(width 0.1)
				(type default)
			)
			(layer "B.Fab")
		)
		(fp_line
			(start 0.12065 -0.305054)
			(end 0.12065 -0.2794)
			(stroke
				(width 0.1)
				(type default)
			)
			(layer "B.Fab")
		)
		(fp_line
			(start -0.120396 0.3048)
			(end -0.120396 0.2794)
			(stroke
				(width 0.1)
				(type default)
			)
			(layer "B.Fab")
		)
		(fp_line
			(start -0.120396 0.2794)
			(end 0.12065 0.2794)
			(stroke
				(width 0.1)
				(type default)
			)
			(layer "B.Fab")
		)
		(fp_line
			(start -0.12065 -0.2794)
			(end -0.12065 -0.3048)
			(stroke
				(width 0.1)
				(type default)
			)
			(layer "B.Fab")
		)
		(fp_line
			(start -0.12065 -0.3048)
			(end -0.67945 -0.3048)
			(stroke
				(width 0.1)
				(type default)
			)
			(layer "B.Fab")
		)
		(fp_line
			(start -0.67945 0.3048)
			(end -0.120396 0.3048)
			(stroke
				(width 0.1)
				(type default)
			)
			(layer "B.Fab")
		)
		(fp_line
			(start -0.67945 -0.3048)
			(end -0.67945 0.3048)
			(stroke
				(width 0.1)
				(type default)
			)
			(layer "B.Fab")
		)
		(pad "1" smd circle
			(at 0.40005 0)
			(size 0 0)
			(layers "B.Cu" "B.Mask" "B.Paste")
			(net "RST_RT_CPU0_P2_PERST_R2_N")
		)
		(pad "2" smd circle
			(at -0.40005 0)
			(size 0 0)
			(layers "B.Cu" "B.Mask" "B.Paste")
			(net "RST_RT_CPU0_P2_PERST_R_N")
		)
	)
	(footprint ""
		(layer "B.Cu")
		(at 388.196836 -178.965098 90)
		(property "Reference" "PC555_4"
			(at 0 0 90)
			(layer "B.SilkS")
			(hide yes)
			(effects
				(font
					(size 1.27 1.27)
				)
				(justify mirror)
			)
		)
		(property "Value" ""
			(at 0 0 90)
			(layer "B.Fab")
			(effects
				(font
					(size 1.27 1.27)
				)
				(justify mirror)
			)
		)
		(duplicate_pad_numbers_are_jumpers no)
		(fp_line
			(start 1.524 -0.762)
			(end -1.524 -0.762)
			(stroke
				(width 0.1524)
				(type default)
			)
			(layer "B.SilkS")
		)
		(fp_line
			(start -1.524 -0.762)
			(end -1.524 0.762)
			(stroke
				(width 0.1524)
				(type default)
			)
			(layer "B.SilkS")
		)
		(fp_line
			(start 1.524 0.762)
			(end 1.524 -0.762)
			(stroke
				(width 0.1524)
				(type default)
			)
			(layer "B.SilkS")
		)
		(fp_line
			(start -1.524 0.762)
			(end 1.524 0.762)
			(stroke
				(width 0.1524)
				(type default)
			)
			(layer "B.SilkS")
		)
		(fp_line
			(start 1.1049 -0.724916)
			(end 1.1049 0.724916)
			(stroke
				(width 0.1)
				(type default)
			)
			(layer "B.Fab")
		)
		(fp_line
			(start -1.1049 -0.724916)
			(end 1.1049 -0.724916)
			(stroke
				(width 0.1)
				(type default)
			)
			(layer "B.Fab")
		)
		(fp_line
			(start 1.1049 0.724916)
			(end -1.1049 0.724916)
			(stroke
				(width 0.1)
				(type default)
			)
			(layer "B.Fab")
		)
		(fp_line
			(start -1.1049 0.724916)
			(end -1.1049 -0.724916)
			(stroke
				(width 0.1)
				(type default)
			)
			(layer "B.Fab")
		)
		(pad "1" smd rect
			(at 0.889 0 90)
			(size 1.016 1.27)
			(layers "B.Cu" "B.Mask" "B.Paste")
			(net "SW_P12V_AUX_PVDDCR_CPU0_P0_FLT")
		)
		(pad "2" smd rect
			(at -0.889 0 90)
			(size 1.016 1.27)
			(layers "B.Cu" "B.Mask" "B.Paste")
			(net "GND")
		)
	)
)
